(kicad_pcb
	(version 20260206)
	(generator "pcbnew")
	(generator_version "10.0")
	(general
		(thickness 1.6)
		(legacy_teardrops no)
	)
	(paper "A4")
	(title_block
		(title "01162023_DA0F0TEBIF0_F0T_Expander_BD_F_brd_V02_OCP.brd")
		(comment 1 "Grand Teton / footprints 6131-6136 of 9728")
	)
	(layers
		(0 "F.Cu" signal "TOP")
		(4 "In1.Cu" signal "GND")
		(6 "In2.Cu" signal "VCC")
		(8 "In3.Cu" signal "VCC1")
		(10 "In4.Cu" signal "GND1")
		(12 "In5.Cu" signal "IN1")
		(14 "In6.Cu" signal "GND2")
		(16 "In7.Cu" signal "IN2")
		(18 "In8.Cu" signal "GND3")
		(20 "In9.Cu" signal "IN3")
		(22 "In10.Cu" signal "GND4")
		(24 "In11.Cu" signal "IN4")
		(26 "In12.Cu" signal "GND5")
		(28 "In13.Cu" signal "IN5")
		(30 "In14.Cu" signal "GND6")
		(32 "In15.Cu" signal "IN6")
		(34 "In16.Cu" signal "GND7")
		(2 "B.Cu" signal "BOTTOM")
		(9 "F.Adhes" user "F.Adhesive")
		(11 "B.Adhes" user "B.Adhesive")
		(13 "F.Paste" user "Package Geometry/Pastemask Top")
		(15 "B.Paste" user "Package Geometry/Pastemask Bottom")
		(5 "F.SilkS" user "Ref Des/Silkscreen Top")
		(7 "B.SilkS" user "Ref Des/Silkscreen Bottom")
		(1 "F.Mask" user "Board Geometry/Soldermask Top")
		(3 "B.Mask" user "Board Geometry/Soldermask Bottom")
		(17 "Dwgs.User" user "User.Drawings")
		(19 "Cmts.User" user "User.Comments")
		(21 "Eco1.User" user "User.Eco1")
		(23 "Eco2.User" user "User.Eco2")
		(25 "Edge.Cuts" user "Board Geometry/Outline")
		(27 "Margin" user)
		(31 "F.CrtYd" user "Package Geometry/Place Bound Top")
		(29 "B.CrtYd" user "Package Geometry/Place Bound Bottom")
		(35 "F.Fab" user "Ref Des/Assembly Top")
		(33 "B.Fab" user "Ref Des/Assembly Bottom")
	)
	(footprint ""
		(layer "F.Cu")
		(at 255.702054 -254.850646 180)
		(property "Reference" "D3"
			(at 1.182878 -1.273048 0)
			(unlocked yes)
			(layer "F.SilkS")
			(effects
				(font
					(size 0.7874 0.5842)
					(thickness 0.1524)
				)
				(justify left)
			)
		)
		(property "Value" ""
			(at 0 0 180)
			(layer "F.Fab")
			(effects
				(font
					(size 1.27 1.27)
				)
			)
		)
		(duplicate_pad_numbers_are_jumpers no)
		(fp_line
			(start 1.16078 0.4826)
			(end -0.64008 0.4826)
			(stroke
				(width 0.1524)
				(type default)
			)
			(layer "F.SilkS")
		)
		(fp_line
			(start 1.16078 -0.4826)
			(end 1.16078 0.4826)
			(stroke
				(width 0.1524)
				(type default)
			)
			(layer "F.SilkS")
		)
		(fp_line
			(start 1.03378 0.4826)
			(end -0.79248 0.4826)
			(stroke
				(width 0.1524)
				(type default)
			)
			(layer "F.SilkS")
		)
		(fp_line
			(start 1.03378 -0.4826)
			(end 1.03378 0.4826)
			(stroke
				(width 0.1524)
				(type default)
			)
			(layer "F.SilkS")
		)
		(fp_line
			(start 0.90678 0.4826)
			(end -0.90678 0.4826)
			(stroke
				(width 0.1524)
				(type default)
			)
			(layer "F.SilkS")
		)
		(fp_line
			(start 0.90678 -0.4826)
			(end 0.90678 0.4826)
			(stroke
				(width 0.1524)
				(type default)
			)
			(layer "F.SilkS")
		)
		(fp_line
			(start -0.64008 -0.4826)
			(end 1.16078 -0.4826)
			(stroke
				(width 0.1524)
				(type default)
			)
			(layer "F.SilkS")
		)
		(fp_line
			(start -0.79248 -0.4826)
			(end 1.03378 -0.4826)
			(stroke
				(width 0.1524)
				(type default)
			)
			(layer "F.SilkS")
		)
		(fp_line
			(start -0.89408 -0.4826)
			(end 0.90678 -0.4826)
			(stroke
				(width 0.1524)
				(type default)
			)
			(layer "F.SilkS")
		)
		(fp_line
			(start -0.90678 0.4826)
			(end -0.90678 -0.4699)
			(stroke
				(width 0.1524)
				(type default)
			)
			(layer "F.SilkS")
		)
		(fp_line
			(start 0.499872 0.249936)
			(end -0.499872 0.249936)
			(stroke
				(width 0.1)
				(type default)
			)
			(layer "F.Fab")
		)
		(fp_line
			(start 0.499872 -0.249936)
			(end 0.499872 0.249936)
			(stroke
				(width 0.1)
				(type default)
			)
			(layer "F.Fab")
		)
		(fp_line
			(start -0.499872 0.249936)
			(end -0.499872 -0.249936)
			(stroke
				(width 0.1)
				(type default)
			)
			(layer "F.Fab")
		)
		(fp_line
			(start -0.499872 -0.249936)
			(end 0.499872 -0.249936)
			(stroke
				(width 0.1)
				(type default)
			)
			(layer "F.Fab")
		)
		(pad "A" smd rect
			(at -0.47498 0 180)
			(size 0.6096 0.7112)
			(layers "F.Cu" "F.Mask" "F.Paste")
			(net "LED_PEX2_SYS_ERR_N")
		)
		(pad "C" smd rect
			(at 0.47498 0 180)
			(size 0.6096 0.7112)
			(layers "F.Cu" "F.Mask" "F.Paste")
			(net "PEX2_SYS_ERR_3V3_N")
		)
	)
	(footprint ""
		(layer "F.Cu")
		(at 206.623158 -81.627472)
		(property "Reference" "R4305"
			(at 0 0 0)
			(layer "F.SilkS")
			(hide yes)
			(effects
				(font
					(size 1.27 1.27)
				)
			)
		)
		(property "Value" ""
			(at 0 0 0)
			(layer "F.Fab")
			(effects
				(font
					(size 1.27 1.27)
				)
			)
		)
		(duplicate_pad_numbers_are_jumpers no)
		(fp_line
			(start -0.7874 -0.4064)
			(end 0.7874 -0.4064)
			(stroke
				(width 0.1524)
				(type default)
			)
			(layer "F.SilkS")
		)
		(fp_line
			(start -0.7874 0.4064)
			(end -0.7874 -0.4064)
			(stroke
				(width 0.1524)
				(type default)
			)
			(layer "F.SilkS")
		)
		(fp_line
			(start 0.7874 -0.4064)
			(end 0.7874 0.4064)
			(stroke
				(width 0.1524)
				(type default)
			)
			(layer "F.SilkS")
		)
		(fp_line
			(start 0.7874 0.4064)
			(end -0.7874 0.4064)
			(stroke
				(width 0.1524)
				(type default)
			)
			(layer "F.SilkS")
		)
		(fp_line
			(start -0.67945 -0.305054)
			(end -0.12065 -0.305054)
			(stroke
				(width 0.1)
				(type default)
			)
			(layer "F.Fab")
		)
		(fp_line
			(start -0.67945 0.3048)
			(end -0.67945 -0.305054)
			(stroke
				(width 0.1)
				(type default)
			)
			(layer "F.Fab")
		)
		(fp_line
			(start -0.12065 -0.305054)
			(end -0.12065 -0.2794)
			(stroke
				(width 0.1)
				(type default)
			)
			(layer "F.Fab")
		)
		(fp_line
			(start -0.12065 -0.2794)
			(end 0.12065 -0.2794)
			(stroke
				(width 0.1)
				(type default)
			)
			(layer "F.Fab")
		)
		(fp_line
			(start -0.12065 0.2794)
			(end -0.12065 0.3048)
			(stroke
				(width 0.1)
				(type default)
			)
			(layer "F.Fab")
		)
		(fp_line
			(start -0.12065 0.3048)
			(end -0.67945 0.3048)
			(stroke
				(width 0.1)
				(type default)
			)
			(layer "F.Fab")
		)
		(fp_line
			(start 0.120396 0.2794)
			(end -0.12065 0.2794)
			(stroke
				(width 0.1)
				(type default)
			)
			(layer "F.Fab")
		)
		(fp_line
			(start 0.120396 0.3048)
			(end 0.120396 0.2794)
			(stroke
				(width 0.1)
				(type default)
			)
			(layer "F.Fab")
		)
		(fp_line
			(start 0.12065 -0.3048)
			(end 0.67945 -0.3048)
			(stroke
				(width 0.1)
				(type default)
			)
			(layer "F.Fab")
		)
		(fp_line
			(start 0.12065 -0.2794)
			(end 0.12065 -0.3048)
			(stroke
				(width 0.1)
				(type default)
			)
			(layer "F.Fab")
		)
		(fp_line
			(start 0.67945 -0.3048)
			(end 0.67945 0.3048)
			(stroke
				(width 0.1)
				(type default)
			)
			(layer "F.Fab")
		)
		(fp_line
			(start 0.67945 0.3048)
			(end 0.120396 0.3048)
			(stroke
				(width 0.1)
				(type default)
			)
			(layer "F.Fab")
		)
		(pad "1" smd circle
			(at -0.40005 0)
			(size 0 0)
			(layers "F.Cu" "F.Mask" "F.Paste")
			(net "SSD3_LED_R")
		)
		(pad "2" smd circle
			(at 0.40005 0)
			(size 0 0)
			(layers "F.Cu" "F.Mask" "F.Paste")
			(net "SSD3_LED")
		)
	)
	(footprint ""
		(layer "F.Cu")
		(at 460.103728 -309.679086)
		(property "Reference" "PC280"
			(at 0 0 0)
			(layer "F.SilkS")
			(hide yes)
			(effects
				(font
					(size 1.27 1.27)
				)
			)
		)
		(property "Value" ""
			(at 0 0 0)
			(layer "F.Fab")
			(effects
				(font
					(size 1.27 1.27)
				)
			)
		)
		(duplicate_pad_numbers_are_jumpers no)
		(fp_line
			(start -0.7874 -0.4064)
			(end 0.7874 -0.4064)
			(stroke
				(width 0.1524)
				(type default)
			)
			(layer "F.SilkS")
		)
		(fp_line
			(start -0.7874 0.4064)
			(end -0.7874 -0.4064)
			(stroke
				(width 0.1524)
				(type default)
			)
			(layer "F.SilkS")
		)
		(fp_line
			(start 0.7874 -0.4064)
			(end 0.7874 0.4064)
			(stroke
				(width 0.1524)
				(type default)
			)
			(layer "F.SilkS")
		)
		(fp_line
			(start 0.7874 0.4064)
			(end -0.7874 0.4064)
			(stroke
				(width 0.1524)
				(type default)
			)
			(layer "F.SilkS")
		)
		(fp_line
			(start -0.67945 -0.305054)
			(end -0.12065 -0.305054)
			(stroke
				(width 0.1)
				(type default)
			)
			(layer "F.Fab")
		)
		(fp_line
			(start -0.67945 0.3048)
			(end -0.67945 -0.305054)
			(stroke
				(width 0.1)
				(type default)
			)
			(layer "F.Fab")
		)
		(fp_line
			(start -0.12065 -0.305054)
			(end -0.12065 -0.2794)
			(stroke
				(width 0.1)
				(type default)
			)
			(layer "F.Fab")
		)
		(fp_line
			(start -0.12065 -0.2794)
			(end 0.12065 -0.2794)
			(stroke
				(width 0.1)
				(type default)
			)
			(layer "F.Fab")
		)
		(fp_line
			(start -0.12065 0.2794)
			(end -0.12065 0.3048)
			(stroke
				(width 0.1)
				(type default)
			)
			(layer "F.Fab")
		)
		(fp_line
			(start -0.12065 0.3048)
			(end -0.67945 0.3048)
			(stroke
				(width 0.1)
				(type default)
			)
			(layer "F.Fab")
		)
		(fp_line
			(start 0.120396 0.2794)
			(end -0.12065 0.2794)
			(stroke
				(width 0.1)
				(type default)
			)
			(layer "F.Fab")
		)
		(fp_line
			(start 0.120396 0.3048)
			(end 0.120396 0.2794)
			(stroke
				(width 0.1)
				(type default)
			)
			(layer "F.Fab")
		)
		(fp_line
			(start 0.12065 -0.3048)
			(end 0.67945 -0.3048)
			(stroke
				(width 0.1)
				(type default)
			)
			(layer "F.Fab")
		)
		(fp_line
			(start 0.12065 -0.2794)
			(end 0.12065 -0.3048)
			(stroke
				(width 0.1)
				(type default)
			)
			(layer "F.Fab")
		)
		(fp_line
			(start 0.67945 -0.3048)
			(end 0.67945 0.3048)
			(stroke
				(width 0.1)
				(type default)
			)
			(layer "F.Fab")
		)
		(fp_line
			(start 0.67945 0.3048)
			(end 0.120396 0.3048)
			(stroke
				(width 0.1)
				(type default)
			)
			(layer "F.Fab")
		)
		(pad "1" smd circle
			(at -0.40005 0)
			(size 0 0)
			(layers "F.Cu" "F.Mask" "F.Paste")
			(net "P1V25_PEX3_FB")
		)
		(pad "2" smd circle
			(at 0.40005 0)
			(size 0 0)
			(layers "F.Cu" "F.Mask" "F.Paste")
			(net "SH_P1V25_PEX3_FB_P")
		)
	)
	(footprint ""
		(layer "F.Cu")
		(at 233.444288 -97.258378 90)
		(property "Reference" "R1007"
			(at 0 0 90)
			(layer "F.SilkS")
			(hide yes)
			(effects
				(font
					(size 1.27 1.27)
				)
			)
		)
		(property "Value" ""
			(at 0 0 90)
			(layer "F.Fab")
			(effects
				(font
					(size 1.27 1.27)
				)
			)
		)
		(duplicate_pad_numbers_are_jumpers no)
		(fp_line
			(start 0.7874 -0.4064)
			(end 0.7874 0.4064)
			(stroke
				(width 0.1524)
				(type default)
			)
			(layer "F.SilkS")
		)
		(fp_line
			(start -0.7874 -0.4064)
			(end 0.7874 -0.4064)
			(stroke
				(width 0.1524)
				(type default)
			)
			(layer "F.SilkS")
		)
		(fp_line
			(start 0.7874 0.4064)
			(end -0.7874 0.4064)
			(stroke
				(width 0.1524)
				(type default)
			)
			(layer "F.SilkS")
		)
		(fp_line
			(start -0.7874 0.4064)
			(end -0.7874 -0.4064)
			(stroke
				(width 0.1524)
				(type default)
			)
			(layer "F.SilkS")
		)
		(fp_line
			(start -0.12065 -0.305054)
			(end -0.12065 -0.2794)
			(stroke
				(width 0.1)
				(type default)
			)
			(layer "F.Fab")
		)
		(fp_line
			(start -0.67945 -0.305054)
			(end -0.12065 -0.305054)
			(stroke
				(width 0.1)
				(type default)
			)
			(layer "F.Fab")
		)
		(fp_line
			(start 0.67945 -0.3048)
			(end 0.67945 0.3048)
			(stroke
				(width 0.1)
				(type default)
			)
			(layer "F.Fab")
		)
		(fp_line
			(start 0.12065 -0.3048)
			(end 0.67945 -0.3048)
			(stroke
				(width 0.1)
				(type default)
			)
			(layer "F.Fab")
		)
		(fp_line
			(start 0.12065 -0.2794)
			(end 0.12065 -0.3048)
			(stroke
				(width 0.1)
				(type default)
			)
			(layer "F.Fab")
		)
		(fp_line
			(start -0.12065 -0.2794)
			(end 0.12065 -0.2794)
			(stroke
				(width 0.1)
				(type default)
			)
			(layer "F.Fab")
		)
		(fp_line
			(start 0.120396 0.2794)
			(end -0.12065 0.2794)
			(stroke
				(width 0.1)
				(type default)
			)
			(layer "F.Fab")
		)
		(fp_line
			(start -0.12065 0.2794)
			(end -0.12065 0.3048)
			(stroke
				(width 0.1)
				(type default)
			)
			(layer "F.Fab")
		)
		(fp_line
			(start 0.67945 0.3048)
			(end 0.120396 0.3048)
			(stroke
				(width 0.1)
				(type default)
			)
			(layer "F.Fab")
		)
		(fp_line
			(start 0.120396 0.3048)
			(end 0.120396 0.2794)
			(stroke
				(width 0.1)
				(type default)
			)
			(layer "F.Fab")
		)
		(fp_line
			(start -0.12065 0.3048)
			(end -0.67945 0.3048)
			(stroke
				(width 0.1)
				(type default)
			)
			(layer "F.Fab")
		)
		(fp_line
			(start -0.67945 0.3048)
			(end -0.67945 -0.305054)
			(stroke
				(width 0.1)
				(type default)
			)
			(layer "F.Fab")
		)
		(pad "1" smd circle
			(at -0.40005 0 90)
			(size 0 0)
			(layers "F.Cu" "F.Mask" "F.Paste")
			(net "PEX_USB_HUB_TEST")
		)
		(pad "2" smd circle
			(at 0.40005 0 90)
			(size 0 0)
			(layers "F.Cu" "F.Mask" "F.Paste")
			(net "GND")
		)
	)
	(footprint ""
		(layer "F.Cu")
		(at 47.961042 -37.951156)
		(property "Reference" "Q135"
			(at 0.287274 -2.501138 0)
			(unlocked yes)
			(layer "F.SilkS")
			(effects
				(font
					(size 0.7874 0.5842)
					(thickness 0.1524)
				)
			)
		)
		(property "Value" ""
			(at 0 0 0)
			(layer "F.Fab")
			(effects
				(font
					(size 1.27 1.27)
				)
			)
		)
		(duplicate_pad_numbers_are_jumpers no)
		(fp_line
			(start -1.376172 -1.199896)
			(end -0.508 -1.199896)
			(stroke
				(width 0.1524)
				(type default)
			)
			(layer "F.SilkS")
		)
		(fp_line
			(start -1.376172 1.199896)
			(end -1.376172 -1.199896)
			(stroke
				(width 0.1524)
				(type default)
			)
			(layer "F.SilkS")
		)
		(fp_line
			(start -0.508 -1.199896)
			(end 0 -0.762)
			(stroke
				(width 0.1524)
				(type default)
			)
			(layer "F.SilkS")
		)
		(fp_line
			(start 0 -0.762)
			(end 0.508 -1.199896)
			(stroke
				(width 0.1524)
				(type default)
			)
			(layer "F.SilkS")
		)
		(fp_line
			(start 0.508 -1.199896)
			(end 1.376172 -1.199896)
			(stroke
				(width 0.1524)
				(type default)
			)
			(layer "F.SilkS")
		)
		(fp_line
			(start 1.376172 -1.199896)
			(end 1.376172 1.199896)
			(stroke
				(width 0.1524)
				(type default)
			)
			(layer "F.SilkS")
		)
		(fp_line
			(start 1.376172 1.199896)
			(end -1.376172 1.199896)
			(stroke
				(width 0.1524)
				(type default)
			)
			(layer "F.SilkS")
		)
		(fp_poly
			(pts
				(xy -1.525778 -1.087882) (xy -1.795272 -1.89611) (xy -2.334006 -1.357376)
			)
			(stroke
				(width 0)
				(type default)
			)
			(fill yes)
			(layer "F.SilkS")
		)
		(fp_line
			(start -0.674878 -1.100074)
			(end 0.674878 -1.100074)
			(stroke
				(width 0.1)
				(type default)
			)
			(layer "F.Fab")
		)
		(fp_line
			(start -0.674878 1.100074)
			(end -0.674878 -1.100074)
			(stroke
				(width 0.1)
				(type default)
			)
			(layer "F.Fab")
		)
		(fp_line
			(start 0.674878 -1.100074)
			(end 0.674878 1.100074)
			(stroke
				(width 0.1)
				(type default)
			)
			(layer "F.Fab")
		)
		(fp_line
			(start 0.674878 1.100074)
			(end -0.674878 1.100074)
			(stroke
				(width 0.1)
				(type default)
			)
			(layer "F.Fab")
		)
		(fp_poly
			(pts
				(xy -1.4605 -0.7493) (xy -2.2225 -1.1303) (xy -2.2225 -0.3683)
			)
			(stroke
				(width 0)
				(type default)
			)
			(fill yes)
			(layer "F.Fab")
		)
		(pad "1" smd rect
			(at -0.899922 -0.750062 270)
			(size 0.6096 0.6096)
			(layers "F.Cu" "F.Mask" "F.Paste")
			(net "GND")
		)
		(pad "2" smd rect
			(at -0.899922 0 270)
			(size 0.4064 0.6096)
			(layers "F.Cu" "F.Mask" "F.Paste")
			(net "P3V3_SSD2_PG_G1")
		)
		(pad "3" smd rect
			(at -0.899922 0.750062 270)
			(size 0.6096 0.6096)
			(layers "F.Cu" "F.Mask" "F.Paste")
			(net "PWRGD_P3V3_SSD2_D")
		)
		(pad "4" smd rect
			(at 0.899922 0.750062 270)
			(size 0.6096 0.6096)
			(layers "F.Cu" "F.Mask" "F.Paste")
			(net "GND")
		)
		(pad "5" smd rect
			(at 0.899922 0 270)
			(size 0.4064 0.6096)
			(layers "F.Cu" "F.Mask" "F.Paste")
			(net "P3V3_SSD2_PG_G2")
		)
		(pad "6" smd rect
			(at 0.899922 -0.750062 270)
			(size 0.6096 0.6096)
			(layers "F.Cu" "F.Mask" "F.Paste")
			(net "P3V3_SSD2_PG_G2")
		)
	)
	(footprint ""
		(layer "F.Cu")
		(at 27.332178 -32.848042 90)
		(property "Reference" "PC677"
			(at 0 0 90)
			(layer "F.SilkS")
			(hide yes)
			(effects
				(font
					(size 1.27 1.27)
				)
			)
		)
		(property "Value" ""
			(at 0 0 90)
			(layer "F.Fab")
			(effects
				(font
					(size 1.27 1.27)
				)
			)
		)
		(duplicate_pad_numbers_are_jumpers no)
		(fp_line
			(start 0.7874 -0.4064)
			(end 0.7874 0.4064)
			(stroke
				(width 0.1524)
				(type default)
			)
			(layer "F.SilkS")
		)
		(fp_line
			(start -0.7874 -0.4064)
			(end 0.7874 -0.4064)
			(stroke
				(width 0.1524)
				(type default)
			)
			(layer "F.SilkS")
		)
		(fp_line
			(start 0.7874 0.4064)
			(end -0.7874 0.4064)
			(stroke
				(width 0.1524)
				(type default)
			)
			(layer "F.SilkS")
		)
		(fp_line
			(start -0.7874 0.4064)
			(end -0.7874 -0.4064)
			(stroke
				(width 0.1524)
				(type default)
			)
			(layer "F.SilkS")
		)
		(fp_line
			(start -0.12065 -0.305054)
			(end -0.12065 -0.2794)
			(stroke
				(width 0.1)
				(type default)
			)
			(layer "F.Fab")
		)
		(fp_line
			(start -0.67945 -0.305054)
			(end -0.12065 -0.305054)
			(stroke
				(width 0.1)
				(type default)
			)
			(layer "F.Fab")
		)
		(fp_line
			(start 0.67945 -0.3048)
			(end 0.67945 0.3048)
			(stroke
				(width 0.1)
				(type default)
			)
			(layer "F.Fab")
		)
		(fp_line
			(start 0.12065 -0.3048)
			(end 0.67945 -0.3048)
			(stroke
				(width 0.1)
				(type default)
			)
			(layer "F.Fab")
		)
		(fp_line
			(start 0.12065 -0.2794)
			(end 0.12065 -0.3048)
			(stroke
				(width 0.1)
				(type default)
			)
			(layer "F.Fab")
		)
		(fp_line
			(start -0.12065 -0.2794)
			(end 0.12065 -0.2794)
			(stroke
				(width 0.1)
				(type default)
			)
			(layer "F.Fab")
		)
		(fp_line
			(start 0.120396 0.2794)
			(end -0.12065 0.2794)
			(stroke
				(width 0.1)
				(type default)
			)
			(layer "F.Fab")
		)
		(fp_line
			(start -0.12065 0.2794)
			(end -0.12065 0.3048)
			(stroke
				(width 0.1)
				(type default)
			)
			(layer "F.Fab")
		)
		(fp_line
			(start 0.67945 0.3048)
			(end 0.120396 0.3048)
			(stroke
				(width 0.1)
				(type default)
			)
			(layer "F.Fab")
		)
		(fp_line
			(start 0.120396 0.3048)
			(end 0.120396 0.2794)
			(stroke
				(width 0.1)
				(type default)
			)
			(layer "F.Fab")
		)
		(fp_line
			(start -0.12065 0.3048)
			(end -0.67945 0.3048)
			(stroke
				(width 0.1)
				(type default)
			)
			(layer "F.Fab")
		)
		(fp_line
			(start -0.67945 0.3048)
			(end -0.67945 -0.305054)
			(stroke
				(width 0.1)
				(type default)
			)
			(layer "F.Fab")
		)
		(pad "1" smd circle
			(at -0.40005 0 90)
			(size 0 0)
			(layers "F.Cu" "F.Mask" "F.Paste")
			(net "P3V3_SSD1_CO_DV_DT")
		)
		(pad "2" smd circle
			(at 0.40005 0 90)
			(size 0 0)
			(layers "F.Cu" "F.Mask" "F.Paste")
			(net "GND")
		)
	)
)
